# S9S_MB_2U (Grand Teton) — schematic parts with pin connectivity, parts 4403–4545 of 6093; source: Cadence DE-HDL packaged netlist (pstxprt.dat, pstxnet.dat, pstchip.dat)

R2454  Q_RES  33.2 1% CHIP  pkg 0402LF  page 241 : 1 = SMB_VR_3V3AUX_SDA_R ; 2 = SMB_VR_3V3AUX_SDA_R2
R2455  Q_RES  33.2 1% CHIP  pkg 0402LF  page 241 : 1 = SMB_VR_3V3AUX_SCL_R ; 2 = SMB_VR_3V3AUX_SCL_R3
R2456  Q_RES  33.2 1% CHIP  pkg 0402LF  page 241 : 1 = SMB_VR_3V3AUX_SDA_R ; 2 = SMB_VR_3V3AUX_SDA_R3
R2457  Q_RES  100K 1% CHIP  pkg 0402LF  page 191 : 1 = E1S_0_EN ; 2 = GND
R2473  Q_RES  49.9 1% CHIP  pkg 0402LF  page 154 : 1 = FB_BMC_ISOLATE_R1 ; 2 = FB_BMC_ISOLATE
R2474  Q_RES  0 5% EMPTY  pkg 0402LF  page 154 : 1 = FM_NCSI_OCP_V3_1_R_OE ; 2 = FB_BMC_ISOLATE
R2476  Q_RES  200K 1% EMPTY  pkg 0402LF  page 194 : 1 = SMB_PCIE_M2_0_EN ; 2 = PWRGD_P1V8_PCH_AUX
R2477  Q_RES  33.2 1% CHIP  pkg 0402LF  page 235 : 1 = SMB_PEHPCPU0_LVC3_SCL_R0 ; 2 = SMB_PEHPCPU0_LVC3_SCL
R2478  Q_RES  33.2 1% CHIP  pkg 0402LF  page 235 : 1 = SMB_PEHPCPU0_LVC3_SDA_R0 ; 2 = SMB_PEHPCPU0_LVC3_SDA
R2479  Q_RES  33.2 1% CHIP  pkg 0402LF  page 235 : 1 = SMB_PEHPCPU1_LVC3_SCL_R0 ; 2 = SMB_PEHPCPU1_LVC3_SCL
R2480  Q_RES  33.2 1% CHIP  pkg 0402LF  page 235 : 1 = SMB_PEHPCPU1_LVC3_SDA_R0 ; 2 = SMB_PEHPCPU1_LVC3_SDA
R2481  Q_RES  4.75K 1% EMPTY  pkg 0402LF  page 208 : 1 = P3V3_AUX ; 2 = CLK_CK440_SMB_ADDR1
R2486  Q_RES  10K 1% CHIP  pkg 0402LF  page 244 : 1 = P3V3_AUX ; 2 = PWRGD_P3V3_AUX_R2
R2487  Q_RES  4.7K 1% EMPTY  pkg 0402LF  page 155 : 1 = P3V3_AUX ; 2 = IRQ_LVC3_WAKE_BUF_N
R2488  Q_RES  4.7K 1% CHIP  pkg 0402LF  page 155 : 1 = P3V3_AUX ; 2 = OCP_SFF_WAKE_BUFF_N
R2489  Q_RES  33.2 1% CHIP  pkg 0402LF  page 155 : 1 = IRQ_LVC3_WAKE_BUF_N ; 2 = IRQ_LVC3_WAKE_N
R2490  Q_RES  1K 1% CHIP  pkg 0402LF  page 115 : 1 = PWRGD_FAIL_CPU0_AB ; 2 = PWRGD_FAIL_CPU0_AB_R1
R2491  Q_RES  1K 1% CHIP  pkg 0402LF  page 115 : 1 = PWRGD_FAIL_CPU0_CD ; 2 = PWRGD_FAIL_CPU0_CD_R1
R2492  Q_RES  1K 1% CHIP  pkg 0402LF  page 115 : 1 = PWRGD_FAIL_CPU0_EF ; 2 = PWRGD_FAIL_CPU0_EF_R1
R2493  Q_RES  1K 1% CHIP  pkg 0402LF  page 115 : 1 = PWRGD_FAIL_CPU0_GH ; 2 = PWRGD_FAIL_CPU0_GH_R1
R2494  Q_RES  1K 1% CHIP  pkg 0402LF  page 115 : 1 = PWRGD_FAIL_CPU1_AB ; 2 = PWRGD_FAIL_CPU1_AB_R1
R2495  Q_RES  1K 1% CHIP  pkg 0402LF  page 115 : 1 = PWRGD_FAIL_CPU1_CD ; 2 = PWRGD_FAIL_CPU1_CD_R1
R2496  Q_RES  1K 1% CHIP  pkg 0402LF  page 115 : 1 = PWRGD_FAIL_CPU1_EF ; 2 = PWRGD_FAIL_CPU1_EF_R1
R2497  Q_RES  1K 1% CHIP  pkg 0402LF  page 115 : 1 = PWRGD_FAIL_CPU1_GH ; 2 = PWRGD_FAIL_CPU1_GH_R1
R2498  Q_RES  33.2 1% CHIP  pkg 0402LF  page 115 : 1 = PWRGD_FAIL_CPU0_AB_R1 ; 2 = PWRGD_FAIL_CPU0_AB_R
R2499  Q_RES  33.2 1% CHIP  pkg 0402LF  page 115 : 1 = PWRGD_FAIL_CPU0_CD_R1 ; 2 = PWRGD_FAIL_CPU0_CD_R
R2500  Q_RES  33.2 1% CHIP  pkg 0402LF  page 115 : 1 = PWRGD_FAIL_CPU0_EF_R1 ; 2 = PWRGD_FAIL_CPU0_EF_R
R2501  Q_RES  33.2 1% CHIP  pkg 0402LF  page 115 : 1 = PWRGD_FAIL_CPU0_GH_R1 ; 2 = PWRGD_FAIL_CPU0_GH_R
R2502  Q_RES  33.2 1% CHIP  pkg 0402LF  page 115 : 1 = PWRGD_FAIL_CPU1_AB_R1 ; 2 = PWRGD_FAIL_CPU1_AB_R
R2503  Q_RES  33.2 1% CHIP  pkg 0402LF  page 115 : 1 = PWRGD_FAIL_CPU1_CD_R1 ; 2 = PWRGD_FAIL_CPU1_CD_R
R2504  Q_RES  33.2 1% CHIP  pkg 0402LF  page 115 : 1 = PWRGD_FAIL_CPU1_EF_R1 ; 2 = PWRGD_FAIL_CPU1_EF_R
R2505  Q_RES  33.2 1% CHIP  pkg 0402LF  page 115 : 1 = PWRGD_FAIL_CPU1_GH_R1 ; 2 = PWRGD_FAIL_CPU1_GH_R
R2506  Q_RES  1K 1% CHIP  pkg 0402LF  page 239 : 1 = P3V3_AUX ; 2 = JTAG_BMC_DBP_TMS
R2507  Q_RES  1K 1% CHIP  pkg 0402LF  page 239 : 1 = P3V3_AUX ; 2 = JTAG_BMC_DBP_TDI
R2508  Q_RES  10K 1% EMPTY  pkg 0402LF  page 184 : 1 = P3V3_AUX ; 2 = FM_M2_SSD0_E7_PEDET
R2509  Q_RES  1K 1% EMPTY  pkg 0402LF  page 184 : 1 = FM_M2_SSD0_E7_PEDET ; 2 = GND
R2510  Q_RES  10K 1% EMPTY  pkg 0402LF  page 184 : 1 = P3V3_AUX ; 2 = FM_M2_E1S_E6_PEDET
R2511  Q_RES  1K 1% EMPTY  pkg 0402LF  page 184 : 1 = FM_M2_E1S_E6_PEDET ; 2 = GND
R2512  Q_RES  49.9 1% CHIP  pkg 0402LF  page 239 : 1 = P1V05_PCH_AUX ; 2 = P0V7_JTAG_VREF_2
R2513  Q_RES  0 5% CHIP  pkg 0402LF  page 239 : 1 = PD_GTL2014_BMC_JTAG_DIR_2 ; 2 = GND
R2514  Q_RES  1K 1% EMPTY  pkg 0402LF  page 239 : 1 = PU_GTL2014_BMC_JTAG_DIR_1 ; 2 = GND
R2520  Q_RES  0 5% CHIP  pkg 0402LF  page 284 : 1 = SMB_VR_3V3AUX_SCL_R3 ; 2 = SMB_CLK_PVCCIN_CPU1
R2521  Q_RES  0 5% CHIP  pkg 0402LF  page 284 : 1 = SMB_VR_3V3AUX_SDA_R3 ; 2 = SMB_DIO_PVCCIN_CPU1
R2522  Q_RES  1K 1% CHIP  pkg 0402LF  page 284 : 1 = P3V3_AUX ; 2 = IRQ_PVCCIN_CPU1_VRHOT_R_N
R2523  Q_RES  0 5% CHIP  pkg 0402LF  page 284 : 1 = IRQ_PVCCIN_CPU1_VRHOT_R_N ; 2 = IRQ_PVCCIN_CPU1_VRHOT_N
R2524  Q_RES  1K 1% CHIP  pkg 0402LF  page 284 : 1 = P3V3_AUX ; 2 = PVCCIN_CPU1_VR_FAULT
R2525  Q_RES  1K 1% CHIP  pkg 0402LF  page 284 : 1 = P3V3_AUX ; 2 = PVCCIN_CPU1_PIN_ALERT
R2526  Q_RES  0 5% CHIP  pkg 0402LF  page 190 : 1 = FM_M2_SSD_0_PEDET ; 2 = FM_M2_SSD0_E7_PEDET
R2528  Q_RES  100K 1% CHIP  pkg 0402LF  page 247 : 1 = P12V_AUX ; 2 = FM_P12V_HSC_EN_N
R2529  Q_RES  0 5% CHIP  pkg 0402LF  page 247 : 1 = FM_P12V_HSC_EN_N ; 2 = FM_P12V_HSC_EN_R_N
R2530  Q_RES  4.7K 5% CHIP  pkg 0402LF  page 247 : 1 = P12V_AUX ; 2 = P12V_AUX_BLEEDING
R2531  Q_RES  0 5% CHIP  pkg 0402LF  page 247 : 1 = MB0_P12V_STBY_PWRGD ; 2 = FM_P12V_HSC_EN_R
R2550  Q_RES  0 5% CHIP  pkg 0402LF  page 284 : 1 = FM_PVCCFA_EHV_FIVRA_CPU1_EN ; 2 = PVCCFA_EHV_FIVRA_CPU1_EN_R
R2551  Q_RES  1K 1% CHIP  pkg 0402LF  page 284 : 1 = P3V3_AUX ; 2 = PWRGD_PVCCFA_EHV_FIVRA_CPU1_R
R2552  Q_RES  0 5% CHIP  pkg 0402LF  page 284 : 1 = PWRGD_PVCCFA_EHV_FIVRA_CPU1 ; 2 = PWRGD_PVCCFA_EHV_FIVRA_CPU1_R
R2553  Q_RES  100 1% CHIP  pkg 0402LF  page 284 : 1 = SVID_DIO0_CPU1_R ; 2 = PVNN_TERM_CPU1
R2554  Q_RES  49.9 1% CHIP  pkg 0402LF  page 284 : 1 = SVID_CLK0_CPU1_R ; 2 = PVNN_TERM_CPU1
R2555  Q_RES  49.9 1% EMPTY  pkg 0402LF  page 284 : 1 = SVID_ALERT0_CPU1_R_N ; 2 = PVNN_TERM_CPU1
R2556  Q_RES  1K 1% CHIP  pkg 0402LF  page 292 : 1 = P3V3_AUX ; 2 = PWRGD_PVCCINFAON_CPU1_R
R2557  Q_RES  0 5% CHIP  pkg 0402LF  page 296 : 1 = IRQ_PVCCD_CPU1_VRHOT_LVC3_R_N ; 2 = IRQ_PVCCD_CPU1_VRHOT_LVC3_N
R2558  Q_RES  0 5% CHIP  pkg 0402LF  page 292 : 1 = FM_PVCCINFAON_CPU1_EN ; 2 = PVCCINFAON_CPU1_EN_R
R2559  Q_RES  150 1% CHIP  pkg 0402LF  page 292 : 1 = SVID_CLK0_CPU1_R ; 2 = SVID_CLK_PVCCINFAON_CPU1_R
R2560  Q_RES  0 5% CHIP  pkg 0402LF  page 292 : 1 = SVID_DIO0_CPU1_R ; 2 = SVID_DIO_PVCCINFAON_CPU1_R
R2561  Q_RES  0 5% CHIP  pkg 0402LF  page 292 : 1 = SVID_ALERT0_CPU1_R_N ; 2 = SVID_ALERT_PVCCINFAON_CPU1_R
R2562  Q_RES  0 5% CHIP  pkg 0402LF  page 206 : 1 = OCP_SFF_CLK_OE_N ; 2 = FM_DB2000_10_OE_N
R2563  Q_RES  0 5% CHIP  pkg 0402LF  page 292 : 1 = SMB_VR_3V3AUX_SDA_R ; 2 = SMB_DIO_PVCCINFAON_CPU1
R2565  Q_RES  0 5% CHIP  pkg 0402LF  page 231 : 1 = SMB_FRU_3V3AUX_SCL_R ; 2 = SMB_FRU_3V3AUX_SCL
R2566  Q_RES  0 5% CHIP  pkg 0402LF  page 231 : 1 = SMB_FRU_3V3AUX_SDA_R ; 2 = SMB_FRU_3V3AUX_SDA
R2568  Q_RES  1K 1% CHIP  pkg 0402LF  page 292 : 1 = P3V3_AUX ; 2 = PVCCINFAON_CPU1_VR_FAULT
R2569  Q_RES  1K 1% CHIP  pkg 0402LF  page 292 : 1 = P3V3_AUX ; 2 = PVCCINFAON_CPU1_PIN_ALERT
R2570  Q_RES  0 5% CHIP  pkg 0402LF  page 292 : 1 = FM_PVCCFA_EHV_CPU1_EN ; 2 = PVCCFA_EHV_CPU1_EN_R
R2571  Q_RES  1K 1% CHIP  pkg 0402LF  page 292 : 1 = P3V3_AUX ; 2 = PWRGD_PVCCFA_EHV_CPU1_R
R2572  Q_RES  0 5% CHIP  pkg 0402LF  page 292 : 1 = PWRGD_PVCCFA_EHV_CPU1 ; 2 = PWRGD_PVCCFA_EHV_CPU1_R
R2573  Q_RES  1K 1% CHIP  pkg 0402LF  page 292 : 1 = P3V3_AUX ; 2 = IRQ_PVCCFA_CPU1_VRHOT_R_N
R2574  Q_RES  0 5% CHIP  pkg 0402LF  page 292 : 1 = IRQ_PVCCFA_CPU1_VRHOT_N ; 2 = IRQ_PVCCFA_CPU1_VRHOT_R_N
R2575  Q_RES  1K 1% CHIP  pkg 0402LF  page 296 : 1 = P3V3_AUX ; 2 = PWRGD_PVCCD_HV_CPU1_R
R2576  Q_RES  0 5% CHIP  pkg 0402LF  page 296 : 1 = PWRGD_PVCCD_HV_CPU1 ; 2 = PWRGD_PVCCD_HV_CPU1_R
R2577  Q_RES  0 5% CHIP  pkg 0402LF  page 296 : 1 = FM_PVCCD_HV_CPU1_EN ; 2 = PVCCD_HV_CPU1_EN_R
R2578  Q_RES  150 1% CHIP  pkg 0402LF  page 296 : 1 = SVID_CLK1_CPU1_R ; 2 = SVID_CLK_PVCCD_HV_CPU1_R
R2579  Q_RES  0 5% CHIP  pkg 0402LF  page 296 : 1 = SVID_DIO1_CPU1_R ; 2 = SVID_DIO_PVCCD_HV_CPU1_R
R2580  Q_RES  0 5% CHIP  pkg 0402LF  page 296 : 1 = SVID_ALERT1_CPU1_R_N ; 2 = SVID_ALERT_PVCCD_HV_CPU1_R
R2582  Q_RES  0 5% CHIP  pkg 0402LF  page 296 : 1 = SMB_VR_3V3AUX_SDA_R ; 2 = SMB_DIO_PVCCD_HV_CPU1
R2583  Q_RES  10K 1% CHIP  pkg 0402LF  page 299 : 1 = P3V3_AUX ; 2 = PWRGD_PVPP_HBM_CPU1_R
R2584  Q_RES  10K 1% CHIP  pkg 0402LF  page 300 : 1 = P3V3_AUX ; 2 = PWRGD_PVNN_MAIN_CPU1_R
R2585  Q_RES  31.6K 1% CHIP  pkg 0402LF  page 301 : 1 = HSC_EN ; 2 = GND
R2586  Q_RES  0 5% CHIP  pkg 0402LF  page 301 : 1 = HSC_EN ; 2 = HSC_EN_R
R2587  Q_RES  4.7K 1% CHIP  pkg 0402LF  page 301 : 1 = HSC_VDD ; 2 = IRQ_HSC_FAULT_N
R2588  Q_RES  22 1% CHIP  pkg 0402LF  page 301 : 1 = HSC_FAULT ; 2 = IRQ_HSC_FAULT_N
R2589  Q_RES  1K 1% CHIP  pkg 0402LF  page 266 : 1 = P3V3_AUX ; 2 = PVCCIN_CPU0_VR_FAULT
R2590  Q_RES  100 1% CHIP  pkg 0402LF  page 266 : 1 = SVID_DIO0_CPU0_R ; 2 = PVNN_TERM_CPU0
R2591  Q_RES  0 5% CHIP  pkg 0402LF  page 266 : 1 = FM_PVCCIN_CPU0_EN ; 2 = PVCCIN_CPU0_EN_R
R2593  Q_RES  100 1% CHIP  pkg 0402LF  page 296 : 1 = PVNN_TERM_CPU1 ; 2 = SVID_DIO1_CPU1_R
R2594  Q_RES  0 5% CHIP  pkg 0402LF  page 274 : 1 = FM_PVCCINFAON_CPU0_EN ; 2 = PVCCINFAON_CPU0_EN_R
R2595  Q_RES  0 5% CHIP  pkg 0402LF  page 274 : 1 = PWRGD_PVCCINFAON_CPU0 ; 2 = PWRGD_PVCCINFAON_CPU0_R
R2596  Q_RES  150 1% CHIP  pkg 0402LF  page 274 : 1 = SVID_CLK0_CPU0_R ; 2 = SVID_CLK_PVCCINFAON_CPU0_R
R2597  Q_RES  0 5% CHIP  pkg 0402LF  page 274 : 1 = IRQ_PVCCFA_CPU0_VRHOT_N ; 2 = IRQ_PVCCFA_CPU0_VRHOT_R_N
R2656  Q_RES  100 1% EMPTY  pkg 0402LF  page 144 : 1 = HGX_DETECT_N_ISO ; 2 = GND
R2659  Q_RES  0 5% CHIP  pkg 0402LF  page 207 : 1 = CLK_100M_SWB_R_DP ; 2 = CLK_100M_SWB_DP
R2660  Q_RES  0 5% CHIP  pkg 0402LF  page 207 : 1 = CLK_100M_SWB_R_DN ; 2 = CLK_100M_SWB_DN
R2661  Q_RES  33.2 1% CHIP  pkg 0402LF  page 213 : 1 = FM_SWB_PWR_EN ; 2 = FM_SWB_PWR_EN_R
R2662  Q_RES  33.2 1% CHIP  pkg 0402LF  page 213 : 1 = FM_GPU_PWR_EN ; 2 = FM_GPU_PWR_EN_R
R2663  Q_RES  33.2 1% CHIP  pkg 0402LF  page 213 : 1 = FM_SWB_PWRGD_ISO ; 2 = FM_SWB_PWRGD_ISO_R
R2664  Q_RES  33.2 1% CHIP  pkg 0402LF  page 213 : 1 = FM_GPU_PWRGD_ISO ; 2 = FM_GPU_PWRGD_ISO_R
R2666  Q_RES  10K 1% CHIP  pkg 0402LF  page 234 : 1 = SMB_BMC_SWB_EN ; 2 = GND
R2667  Q_RES  10K 1% CHIP  pkg 0402LF  page 234 : 1 = P3V3_AUX ; 2 = SMB_BMC_SWB_BUF_R_SCL
R2668  Q_RES  4.7K 5% EMPTY  pkg 0402LF  page 234 : 1 = P3V3_AUX ; 2 = I3C_BMC_SWB_BUF_R_SDA
R2669  Q_RES  10K 1% CHIP  pkg 0402LF  page 234 : 1 = P3V3_AUX ; 2 = SMB_BMC_SWB_BUF_R_SDA
R2670  Q_RES  4.7K 5% EMPTY  pkg 0402LF  page 234 : 1 = P3V3_AUX ; 2 = I3C_BMC_SWB_BUF_R_SCL
R2671  Q_RES  33.2 1% CHIP  pkg 0402LF  page 234 : 1 = SMB_BMC_SWB_BUF_R_SCL ; 2 = SMB_BMC_SWB_BUF_SCL
R2672  Q_RES  33.2 1% CHIP  pkg 0402LF  page 234 : 1 = SMB_BMC_SWB_BUF_R_SDA ; 2 = SMB_BMC_SWB_BUF_SDA
R2674  Q_RES  27.4 1% CHIP  pkg 0402LF  page 234 : 1 = I3C_BMC_SWB_BUF_R_SDA ; 2 = I3C_BMC_SWB_BUF_SDA
R2675  Q_RES  33.2 1% CHIP  pkg 0402LF  page 234 : 1 = I3C_BMC_SWB_BUF_R_SCL ; 2 = I3C_BMC_SWB_BUF_SCL
R2676  Q_RES  0 5% CHIP  pkg 0402LF  page 234 : 1 = SMB_BMC_SWB_EN ; 2 = SMB_BMC_SWB_EN_R2
R2693  Q_RES  1K 1% EMPTY  pkg 0402LF  page 227 : 1 = P3V3_AUX ; 2 = TCA9539_0_ADD1
R2694  Q_RES  1K 1% CHIP  pkg 0402LF  page 227 : 1 = TCA9539_0_ADD1 ; 2 = GND
R2695  Q_RES  1K 1% EMPTY  pkg 0402LF  page 227 : 1 = P3V3_AUX ; 2 = TCA9539_0_ADD0
R2696  Q_RES  1K 1% CHIP  pkg 0402LF  page 227 : 1 = TCA9539_0_ADD0 ; 2 = GND
R2703  Q_RES  0 5% CHIP  pkg 0402LF  page 231 : 1 = SMB_BMC_SWB_SCL_R4 ; 2 = SMB_BMC_SWB_SCL
R2704  Q_RES  0 5% CHIP  pkg 0402LF  page 231 : 1 = SMB_BMC_SWB_SDA_R4 ; 2 = SMB_BMC_SWB_SDA
R2705  Q_RES  0 5% EMPTY  pkg 0402LF  page 234 : 1 = SMB_BMC_SWB_R_SCL ; 2 = SMB_BMC_SWB_BUF_R_SCL
R2706  Q_RES  0 5% CHIP  pkg 0402LF  page 234 : 1 = I3C_BMC_SWB_R_SDA ; 2 = I3C_BMC_SWB_BUF_R_SDA
R2707  Q_RES  0 5% CHIP  pkg 0402LF  page 234 : 1 = SMB_BMC_SWB_EN ; 2 = SMB_BMC_SWB_EN_R
R2724  Q_RES  0 5% EMPTY  pkg 0402LF  page 234 : 1 = SMB_BMC_SWB_R_SDA ; 2 = SMB_BMC_SWB_BUF_R_SDA
R2725  Q_RES  0 5% CHIP  pkg 0402LF  page 234 : 1 = I3C_BMC_SWB_R_SCL ; 2 = I3C_BMC_SWB_BUF_R_SCL
R2726  Q_RES  33.2 1% CHIP  pkg 0402LF  page 114 : 1 = PWRGD_CHA_CPU0_DIMM1 ; 2 = PWRGD_FAIL_CPU0_AB
R2727  Q_RES  33.2 1% CHIP  pkg 0402LF  page 114 : 1 = PWRGD_CHA_CPU0_DIMM2 ; 2 = PWRGD_FAIL_CPU0_AB
R2728  Q_RES  33.2 1% CHIP  pkg 0402LF  page 114 : 1 = PWRGD_CHB_CPU0_DIMM1 ; 2 = PWRGD_FAIL_CPU0_AB
R2729  Q_RES  33.2 1% CHIP  pkg 0402LF  page 114 : 1 = PWRGD_CHC_CPU0_DIMM1 ; 2 = PWRGD_FAIL_CPU0_CD
R2730  Q_RES  33.2 1% CHIP  pkg 0402LF  page 114 : 1 = PWRGD_CHC_CPU0_DIMM2 ; 2 = PWRGD_FAIL_CPU0_CD
R2731  Q_RES  33.2 1% CHIP  pkg 0402LF  page 114 : 1 = PWRGD_CHD_CPU0_DIMM1 ; 2 = PWRGD_FAIL_CPU0_CD
R2732  Q_RES  33.2 1% CHIP  pkg 0402LF  page 114 : 1 = PWRGD_CHF_CPU0_DIMM1 ; 2 = PWRGD_FAIL_CPU0_EF
R2733  Q_RES  33.2 1% CHIP  pkg 0402LF  page 114 : 1 = PWRGD_CHF_CPU0_DIMM2 ; 2 = PWRGD_FAIL_CPU0_EF
R2734  Q_RES  33.2 1% CHIP  pkg 0402LF  page 114 : 1 = PWRGD_CHH_CPU0_DIMM1 ; 2 = PWRGD_FAIL_CPU0_GH
R2735  Q_RES  33.2 1% CHIP  pkg 0402LF  page 114 : 1 = PWRGD_CHH_CPU0_DIMM2 ; 2 = PWRGD_FAIL_CPU0_GH
R2736  Q_RES  33.2 1% CHIP  pkg 0402LF  page 114 : 1 = PWRGD_CHF_CPU1_DIMM2 ; 2 = PWRGD_FAIL_CPU1_EF
R2738  Q_RES  33.2 1% CHIP  pkg 0402LF  page 223 : 1 = RST_PERST_SWB_N ; 2 = RST_PERST_SWB_R_N
R2786  Q_RES  0 5% CHIP  pkg 0402LF  page 152 : 1 = USB2_HUB_SWB_DP ; 2 = USB2_HUB_BUF_SWB_R_DP
R2787  Q_RES  0 5% CHIP  pkg 0402LF  page 152 : 1 = USB2_HUB_SWB_DN ; 2 = USB2_HUB_BUF_SWB_R_DN
R2788  Q_RES  0 5% EMPTY  pkg 0402LF  page 152 : 1 = USB2_HOST_BMC_B_BUF_DP ; 2 = USB2_HUB_BUF_SWB_R_DP
R2789  Q_RES  0 5% EMPTY  pkg 0402LF  page 152 : 1 = USB2_HOST_BMC_B_BUF_DN ; 2 = USB2_HUB_BUF_SWB_R_DN
R2790  Q_RES  0 5% EMPTY  pkg 0402LF  page 152 : 1 = USB2_HOST_BMC_B_DP ; 2 = USB2_HOST_BMC_B_BUF_DP
R2791  Q_RES  0 5% EMPTY  pkg 0402LF  page 152 : 1 = USB2_HOST_BMC_B_DN ; 2 = USB2_HOST_BMC_B_BUF_DN
R2792  Q_RES  0 5% CHIP  pkg 0402LF  page 215 : 1 = FM_PDB_BUF_EN ; 2 = FM_PDB_BUF_EN_R
